(kicad_pcb
	(version 20241229)
	(generator "pcbnew")
	(generator_version "9.0")
	(general
		(thickness 1.6642)
		(legacy_teardrops no)
	)
	(paper "A3")
	(title_block
		(title "PolarFire SoM")
		(date "2025-07-22")
		(rev "1.1.4")
		(company "Antmicro Ltd")
		(comment 1 "www.antmicro.com")
		(comment 9 "footprint 19 of 470 (U26), pads 1-77 of 77")
	)
	(layers
		(0 "F.Cu" mixed)
		(4 "In1.Cu" power)
		(6 "In2.Cu" signal)
		(8 "In3.Cu" power)
		(10 "In4.Cu" signal)
		(12 "In5.Cu" power)
		(14 "In6.Cu" power)
		(16 "In7.Cu" signal)
		(18 "In8.Cu" power)
		(20 "In9.Cu" signal)
		(22 "In10.Cu" power)
		(24 "In11.Cu" signal)
		(26 "In12.Cu" signal)
		(2 "B.Cu" mixed)
		(9 "F.Adhes" user "F.Adhesive")
		(11 "B.Adhes" user "B.Adhesive")
		(13 "F.Paste" user)
		(15 "B.Paste" user)
		(5 "F.SilkS" user "F.Silkscreen")
		(7 "B.SilkS" user "B.Silkscreen")
		(1 "F.Mask" user)
		(3 "B.Mask" user)
		(17 "Dwgs.User" user "User.Drawings")
		(19 "Cmts.User" user "User.Comments")
		(21 "Eco1.User" user "User.Eco1")
		(23 "Eco2.User" user "User.Eco2")
		(25 "Edge.Cuts" user)
		(27 "Margin" user)
		(31 "F.CrtYd" user "F.Courtyard")
		(29 "B.CrtYd" user "B.Courtyard")
		(35 "F.Fab" user)
		(33 "B.Fab" user)
	)
	(footprint "antmicro-footprints:WiFi_Bluetooth_Module_LBEE5PK2AE"
		(layer "F.Cu")
		(at 222.1015 144.442)
		(property "Reference" "U26"
			(at 2.1485 5.028 0)
			(layer "F.SilkS")
			(effects
				(font
					(size 0.7 0.7)
					(thickness 0.15)
				)
				(justify left bottom)
			)
		)
		(property "Value" "WiFi_Bluetooth_LBEE5PK2AE"
			(at 0 5.1 0)
			(layer "F.Fab")
			(hide yes)
			(effects
				(font
					(size 0.7 0.7)
					(thickness 0.15)
				)
				(justify left bottom)
			)
		)
		(property "Datasheet" "https://www.murata.com/products/productdata/8816428220446/type2ae.pdf"
			(at 0 0 0)
			(layer "F.Fab")
			(hide yes)
			(effects
				(font
					(size 1.27 1.27)
					(thickness 0.15)
				)
			)
		)
		(property "Description" "WiFi and Bluetooth Module"
			(at 0 0 0)
			(layer "F.Fab")
			(hide yes)
			(effects
				(font
					(size 1.27 1.27)
					(thickness 0.15)
				)
			)
		)
		(property "Author" "Antmicro"
			(at 0 0 0)
			(layer "F.Fab")
			(hide yes)
			(effects
				(font
					(size 1 1)
					(thickness 0.15)
				)
			)
		)
		(property "License" "Apache-2.0"
			(at 0 0 0)
			(layer "F.Fab")
			(hide yes)
			(effects
				(font
					(size 1 1)
					(thickness 0.15)
				)
			)
		)
		(property "MPN" "LBEE5PK2AE"
			(at 0 0 0)
			(layer "F.Fab")
			(hide yes)
			(effects
				(font
					(size 1 1)
					(thickness 0.15)
				)
			)
		)
		(property "Manufacturer" "Murata"
			(at 0 0 0)
			(layer "F.Fab")
			(hide yes)
			(effects
				(font
					(size 1 1)
					(thickness 0.15)
				)
			)
		)
		(sheetname "/WiFi_Bluetooth/")
		(sheetfile "wifi_bt.kicad_sch")
		(attr smd)
		(pad "1" smd roundrect
			(at -3.3 3.375 180)
			(size 0.3 0.45)
			(layers "F.Cu" "F.Mask" "F.Paste")
			(roundrect_rratio 0.18)
			(net 417 "GND")
			(pinfunction "GND")
			(pintype "power_in")
		)
		(pad "2" smd roundrect
			(at -2.7 3.375 180)
			(size 0.3 0.45)
			(layers "F.Cu" "F.Mask" "F.Paste")
			(roundrect_rratio 0.18)
			(net 220 "Net-(U26A-SR_VLX)")
			(pinfunction "SR_VLX")
			(pintype "power_out")
		)
		(pad "3" smd roundrect
			(at -2.1 3.375 180)
			(size 0.3 0.45)
			(layers "F.Cu" "F.Mask" "F.Paste")
			(roundrect_rratio 0.18)
			(net 50 "+3V3")
			(pinfunction "VBAT")
			(pintype "power_in")
		)
		(pad "4" smd roundrect
			(at -1.5 3.375 180)
			(size 0.3 0.45)
			(layers "F.Cu" "F.Mask" "F.Paste")
			(roundrect_rratio 0.18)
			(net 171 "WL_REG_ON")
			(pinfunction "WL_REG_EN")
			(pintype "input")
		)
		(pad "5" smd roundrect
			(at -0.9 3.375 180)
			(size 0.3 0.45)
			(layers "F.Cu" "F.Mask" "F.Paste")
			(roundrect_rratio 0.18)
			(net 430 "/WiFi_Bluetooth/LPO_IN")
			(pinfunction "LPO_IN")
			(pintype "input")
		)
		(pad "6" smd roundrect
			(at -0.3 3.375 180)
			(size 0.3 0.45)
			(layers "F.Cu" "F.Mask" "F.Paste")
			(roundrect_rratio 0.18)
			(net 507 "Net-(U26A-BT_PCM_IN)")
			(pinfunction "BT_PCM_IN")
			(pintype "input")
		)
		(pad "7" smd roundrect
			(at 0.3 3.375 180)
			(size 0.3 0.45)
			(layers "F.Cu" "F.Mask" "F.Paste")
			(roundrect_rratio 0.18)
			(net 508 "Net-(U26A-BT_PCM_CLK)")
			(pinfunction "BT_PCM_CLK")
			(pintype "bidirectional")
		)
		(pad "8" smd roundrect
			(at 0.9 3.375 180)
			(size 0.3 0.45)
			(layers "F.Cu" "F.Mask" "F.Paste")
			(roundrect_rratio 0.18)
			(net 520 "Net-(U26A-BT_PCM_SYNC)")
			(pinfunction "BT_PCM_SYNC")
			(pintype "bidirectional")
		)
		(pad "9" smd roundrect
			(at 1.5 3.375 180)
			(size 0.3 0.45)
			(layers "F.Cu" "F.Mask" "F.Paste")
			(roundrect_rratio 0.18)
			(net 521 "Net-(U26A-BT_PCM_OUT)")
			(pinfunction "BT_PCM_OUT")
			(pintype "output")
		)
		(pad "10" smd roundrect
			(at 2.1 3.375 180)
			(size 0.3 0.45)
			(layers "F.Cu" "F.Mask" "F.Paste")
			(roundrect_rratio 0.18)
			(net 85 "/FPGA MSSIO/PF_BT.TX")
			(pinfunction "BT_UART_TXD")
			(pintype "output")
		)
		(pad "11" smd roundrect
			(at 2.7 3.375 180)
			(size 0.3 0.45)
			(layers "F.Cu" "F.Mask" "F.Paste")
			(roundrect_rratio 0.18)
			(net 297 "Net-(U26A-BT_UART_CTS_N)")
			(pinfunction "BT_UART_CTS_N")
			(pintype "input")
		)
		(pad "12" smd roundrect
			(at 3.3 3.375 180)
			(size 0.3 0.45)
			(layers "F.Cu" "F.Mask" "F.Paste")
			(roundrect_rratio 0.18)
			(net 117 "/FPGA MSSIO/PF_BT.RX")
			(pinfunction "BT_UART_RXD")
			(pintype "input")
		)
		(pad "13" smd roundrect
			(at 3.475 2.7 90)
			(size 0.3 0.45)
			(layers "F.Cu" "F.Mask" "F.Paste")
			(roundrect_rratio 0.18)
			(net 506 "Net-(U26A-BT_UART_RTS_N)")
			(pinfunction "BT_UART_RTS_N")
			(pintype "output")
		)
		(pad "14" smd roundrect
			(at 3.475 2.1 90)
			(size 0.3 0.45)
			(layers "F.Cu" "F.Mask" "F.Paste")
			(roundrect_rratio 0.18)
			(net 417 "GND")
			(pinfunction "GND")
			(pintype "passive")
		)
		(pad "15" smd roundrect
			(at 3.475 1.5 90)
			(size 0.3 0.45)
			(layers "F.Cu" "F.Mask" "F.Paste")
			(roundrect_rratio 0.18)
		)
		(pad "16" smd roundrect
			(at 3.475 0.9 90)
			(size 0.3 0.45)
			(layers "F.Cu" "F.Mask" "F.Paste")
			(roundrect_rratio 0.18)
			(net 417 "GND")
			(pinfunction "GND")
			(pintype "passive")
		)
		(pad "17" smd roundrect
			(at 3.475 0.3 90)
			(size 0.3 0.45)
			(layers "F.Cu" "F.Mask" "F.Paste")
			(roundrect_rratio 0.18)
			(net 526 "Net-(U26A-BT_HOST_WAKE)")
			(pinfunction "BT_HOST_WAKE")
			(pintype "bidirectional")
		)
		(pad "18" smd roundrect
			(at 3.475 -0.3 90)
			(size 0.3 0.45)
			(layers "F.Cu" "F.Mask" "F.Paste")
			(roundrect_rratio 0.18)
			(net 527 "Net-(U26A-BT_GPIO_2)")
			(pinfunction "BT_GPIO_2")
			(pintype "bidirectional")
		)
		(pad "19" smd roundrect
			(at 3.475 -0.9 90)
			(size 0.3 0.45)
			(layers "F.Cu" "F.Mask" "F.Paste")
			(roundrect_rratio 0.18)
			(net 528 "Net-(U26A-BT_GPIO_3)")
			(pinfunction "BT_GPIO_3")
			(pintype "bidirectional")
		)
		(pad "20" smd roundrect
			(at 3.475 -1.5 90)
			(size 0.3 0.45)
			(layers "F.Cu" "F.Mask" "F.Paste")
			(roundrect_rratio 0.18)
			(net 529 "Net-(U26A-BT_GPIO_5)")
			(pinfunction "BT_GPIO_5")
			(pintype "bidirectional")
		)
		(pad "21" smd roundrect
			(at 3.475 -2.1 90)
			(size 0.3 0.45)
			(layers "F.Cu" "F.Mask" "F.Paste")
			(roundrect_rratio 0.18)
			(net 417 "GND")
			(pinfunction "GND")
			(pintype "passive")
		)
		(pad "22" smd roundrect
			(at 3.475 -2.7 90)
			(size 0.3 0.45)
			(layers "F.Cu" "F.Mask" "F.Paste")
			(roundrect_rratio 0.18)
			(net 232 "Net-(U26A-WL_ANT)")
			(pinfunction "WL_ANT")
			(pintype "bidirectional")
		)
		(pad "23" smd roundrect
			(at 3.3 -3.375 180)
			(size 0.3 0.45)
			(layers "F.Cu" "F.Mask" "F.Paste")
			(roundrect_rratio 0.18)
			(net 417 "GND")
			(pinfunction "GND")
			(pintype "passive")
		)
		(pad "24" smd roundrect
			(at 2.7 -3.375 180)
			(size 0.3 0.45)
			(layers "F.Cu" "F.Mask" "F.Paste")
			(roundrect_rratio 0.18)
			(net 417 "GND")
			(pinfunction "GND")
			(pintype "passive")
		)
		(pad "25" smd roundrect
			(at 2.1 -3.375 180)
			(size 0.3 0.45)
			(layers "F.Cu" "F.Mask" "F.Paste")
			(roundrect_rratio 0.18)
			(net 621 "Net-(U26A-RF_SW_CTRL_5)")
			(pinfunction "RF_SW_CTRL_5")
			(pintype "output")
		)
		(pad "26" smd roundrect
			(at 1.5 -3.375 180)
			(size 0.3 0.45)
			(layers "F.Cu" "F.Mask" "F.Paste")
			(roundrect_rratio 0.18)
			(net 620 "Net-(U26A-RF_SW_CTRL_0)")
			(pinfunction "RF_SW_CTRL_0")
			(pintype "output")
		)
		(pad "27" smd roundrect
			(at 0.9 -3.375 180)
			(size 0.3 0.45)
			(layers "F.Cu" "F.Mask" "F.Paste")
			(roundrect_rratio 0.18)
			(net 417 "GND")
			(pinfunction "GND")
			(pintype "passive")
		)
		(pad "28" smd roundrect
			(at 0.3 -3.375 180)
			(size 0.3 0.45)
			(layers "F.Cu" "F.Mask" "F.Paste")
			(roundrect_rratio 0.18)
			(net 231 "/FPGA GPIO/WiFi.CMD")
			(pinfunction "SDIO_CMD")
			(pintype "bidirectional")
		)
		(pad "29" smd roundrect
			(at -0.3 -3.375 180)
			(size 0.3 0.45)
			(layers "F.Cu" "F.Mask" "F.Paste")
			(roundrect_rratio 0.18)
			(net 226 "/FPGA GPIO/WiFi.DAT1")
			(pinfunction "SDIO_DATA_1")
			(pintype "bidirectional")
		)
		(pad "30" smd roundrect
			(at -0.9 -3.375 180)
			(size 0.3 0.45)
			(layers "F.Cu" "F.Mask" "F.Paste")
			(roundrect_rratio 0.18)
			(net 240 "/FPGA GPIO/WiFi.DAT0")
			(pinfunction "SDIO_DATA_0")
			(pintype "bidirectional")
		)
		(pad "31" smd roundrect
			(at -1.5 -3.375 180)
			(size 0.3 0.45)
			(layers "F.Cu" "F.Mask" "F.Paste")
			(roundrect_rratio 0.18)
			(net 128 "/FPGA GPIO/WiFi.DAT3")
			(pinfunction "SDIO_DATA_3")
			(pintype "bidirectional")
		)
		(pad "32" smd roundrect
			(at -2.1 -3.375 180)
			(size 0.3 0.45)
			(layers "F.Cu" "F.Mask" "F.Paste")
			(roundrect_rratio 0.18)
			(net 225 "/FPGA GPIO/WiFi.DAT2")
			(pinfunction "SDIO_DATA_2")
			(pintype "bidirectional")
		)
		(pad "33" smd roundrect
			(at -2.7 -3.375 180)
			(size 0.3 0.45)
			(layers "F.Cu" "F.Mask" "F.Paste")
			(roundrect_rratio 0.18)
			(net 129 "/FPGA GPIO/WiFi.CLK")
			(pinfunction "SDIO_CLK")
			(pintype "input")
		)
		(pad "34" smd roundrect
			(at -3.3 -3.375 180)
			(size 0.3 0.45)
			(layers "F.Cu" "F.Mask" "F.Paste")
			(roundrect_rratio 0.18)
			(net 417 "GND")
			(pinfunction "GND")
			(pintype "passive")
		)
		(pad "35" smd roundrect
			(at -3.475 -2.7 90)
			(size 0.3 0.45)
			(layers "F.Cu" "F.Mask" "F.Paste")
			(roundrect_rratio 0.18)
		)
		(pad "36" smd roundrect
			(at -3.475 -2.1 90)
			(size 0.3 0.45)
			(layers "F.Cu" "F.Mask" "F.Paste")
			(roundrect_rratio 0.18)
		)
		(pad "37" smd roundrect
			(at -3.475 -1.5 90)
			(size 0.3 0.45)
			(layers "F.Cu" "F.Mask" "F.Paste")
			(roundrect_rratio 0.18)
		)
		(pad "38" smd roundrect
			(at -3.475 -0.9 90)
			(size 0.3 0.45)
			(layers "F.Cu" "F.Mask" "F.Paste")
			(roundrect_rratio 0.18)
		)
		(pad "39" smd roundrect
			(at -3.475 -0.3 90)
			(size 0.3 0.45)
			(layers "F.Cu" "F.Mask" "F.Paste")
			(roundrect_rratio 0.18)
		)
		(pad "40" smd roundrect
			(at -3.475 0.3 90)
			(size 0.3 0.45)
			(layers "F.Cu" "F.Mask" "F.Paste")
			(roundrect_rratio 0.18)
		)
		(pad "41" smd roundrect
			(at -3.475 0.9 90)
			(size 0.3 0.45)
			(layers "F.Cu" "F.Mask" "F.Paste")
			(roundrect_rratio 0.18)
			(net 417 "GND")
			(pinfunction "GND")
			(pintype "passive")
		)
		(pad "42" smd roundrect
			(at -3.475 1.5 90)
			(size 0.3 0.45)
			(layers "F.Cu" "F.Mask" "F.Paste")
			(roundrect_rratio 0.18)
			(net 50 "+3V3")
			(pinfunction "VDDIO")
			(pintype "power_in")
		)
		(pad "43" smd roundrect
			(at -3.475 2.1 90)
			(size 0.3 0.45)
			(layers "F.Cu" "F.Mask" "F.Paste")
			(roundrect_rratio 0.18)
			(net 151 "Net-(U26A-VIN_LDO)")
			(pinfunction "VIN_LDO")
			(pintype "power_in")
		)
		(pad "44" smd roundrect
			(at -3.475 2.7 90)
			(size 0.3 0.45)
			(layers "F.Cu" "F.Mask" "F.Paste")
			(roundrect_rratio 0.18)
		)
		(pad "45" smd roundrect
			(at -1.5 2.175 180)
			(size 0.3 0.45)
			(layers "F.Cu" "F.Mask" "F.Paste")
			(roundrect_rratio 0.18)
			(net 530 "Net-(U26A-GPIO_1)")
			(pinfunction "GPIO_1")
			(pintype "bidirectional")
		)
		(pad "46" smd roundrect
			(at -0.9 2.175 180)
			(size 0.3 0.45)
			(layers "F.Cu" "F.Mask" "F.Paste")
			(roundrect_rratio 0.18)
			(net 122 "/USB/WL_BT.D_N")
			(pinfunction "USB2_DM")
			(pintype "bidirectional")
		)
		(pad "47" smd roundrect
			(at -0.3 2.175 180)
			(size 0.3 0.45)
			(layers "F.Cu" "F.Mask" "F.Paste")
			(roundrect_rratio 0.18)
			(net 190 "/USB/WL_BT.D_P")
			(pinfunction "USB2_DP")
			(pintype "bidirectional")
		)
		(pad "48" smd roundrect
			(at 0.3 2.175 180)
			(size 0.3 0.45)
			(layers "F.Cu" "F.Mask" "F.Paste")
			(roundrect_rratio 0.18)
			(net 534 "unconnected-(U26A-USB2_MONCDR-Pad48)")
			(pinfunction "USB2_MONCDR")
			(pintype "output+no_connect")
		)
		(pad "49" smd roundrect
			(at 0.9 2.175 180)
			(size 0.3 0.45)
			(layers "F.Cu" "F.Mask" "F.Paste")
			(roundrect_rratio 0.18)
			(net 50 "+3V3")
			(pinfunction "USB2_AVDD33")
			(pintype "power_in")
		)
		(pad "50" smd roundrect
			(at 1.5 2.175 180)
			(size 0.3 0.45)
			(layers "F.Cu" "F.Mask" "F.Paste")
			(roundrect_rratio 0.18)
			(net 281 "Net-(U26A-USB2_RREF)")
			(pinfunction "USB2_RREF")
			(pintype "bidirectional")
		)
		(pad "51" smd roundrect
			(at 2.275 1.5 90)
			(size 0.3 0.45)
			(layers "F.Cu" "F.Mask" "F.Paste")
			(roundrect_rratio 0.18)
			(net 524 "Net-(U26A-BT_DEV_WAKE)")
			(pinfunction "BT_DEV_WAKE")
			(pintype "input")
		)
		(pad "52" smd roundrect
			(at 2.275 0.9 90)
			(size 0.3 0.45)
			(layers "F.Cu" "F.Mask" "F.Paste")
			(roundrect_rratio 0.18)
			(net 525 "Net-(U26A-WL_HOST_WAKE)")
			(pinfunction "WL_HOST_WAKE")
			(pintype "output")
		)
		(pad "53" smd roundrect
			(at 2.275 0.3 90)
			(size 0.3 0.45)
			(layers "F.Cu" "F.Mask" "F.Paste")
			(roundrect_rratio 0.18)
			(net 424 "/WiFi_Bluetooth/JTAG_SEL")
			(pinfunction "JTAG_SEL")
			(pintype "input")
		)
		(pad "54" smd roundrect
			(at 2.275 -0.3 90)
			(size 0.3 0.45)
			(layers "F.Cu" "F.Mask" "F.Paste")
			(roundrect_rratio 0.18)
			(net 422 "/WiFi_Bluetooth/STRAP_1")
			(pinfunction "STRAP_1")
			(pintype "input")
		)
		(pad "55" smd roundrect
			(at 2.275 -0.9 90)
			(size 0.3 0.45)
			(layers "F.Cu" "F.Mask" "F.Paste")
			(roundrect_rratio 0.18)
			(net 423 "/WiFi_Bluetooth/STRAP_2")
			(pinfunction "STRAP_2")
			(pintype "input")
		)
		(pad "56" smd roundrect
			(at 2.275 -1.5 90)
			(size 0.3 0.45)
			(layers "F.Cu" "F.Mask" "F.Paste")
			(roundrect_rratio 0.18)
			(net 421 "/WiFi_Bluetooth/STRAP_0")
			(pinfunction "STRAP_0")
			(pintype "input")
		)
		(pad "57" smd roundrect
			(at 1.5 -2.175 180)
			(size 0.3 0.45)
			(layers "F.Cu" "F.Mask" "F.Paste")
			(roundrect_rratio 0.18)
			(net 417 "GND")
			(pinfunction "GND")
			(pintype "passive")
		)
		(pad "58" smd roundrect
			(at 0.9 -2.175 180)
			(size 0.3 0.45)
			(layers "F.Cu" "F.Mask" "F.Paste")
			(roundrect_rratio 0.18)
		)
		(pad "59" smd roundrect
			(at 0.3 -2.175 180)
			(size 0.3 0.45)
			(layers "F.Cu" "F.Mask" "F.Paste")
			(roundrect_rratio 0.18)
		)
		(pad "60" smd roundrect
			(at -0.3 -2.175 180)
			(size 0.3 0.45)
			(layers "F.Cu" "F.Mask" "F.Paste")
			(roundrect_rratio 0.18)
		)
		(pad "61" smd roundrect
			(at -0.9 -2.175 180)
			(size 0.3 0.45)
			(layers "F.Cu" "F.Mask" "F.Paste")
			(roundrect_rratio 0.18)
		)
		(pad "62" smd roundrect
			(at -1.5 -2.175 180)
			(size 0.3 0.45)
			(layers "F.Cu" "F.Mask" "F.Paste")
			(roundrect_rratio 0.18)
		)
		(pad "63" smd roundrect
			(at -2.275 -1.5 90)
			(size 0.3 0.45)
			(layers "F.Cu" "F.Mask" "F.Paste")
			(roundrect_rratio 0.18)
			(net 127 "JTAG_RESET_n")
			(pinfunction "TRST_L")
			(pintype "bidirectional")
		)
		(pad "64" smd roundrect
			(at -2.275 -0.9 90)
			(size 0.3 0.45)
			(layers "F.Cu" "F.Mask" "F.Paste")
			(roundrect_rratio 0.18)
			(net 192 "PF_TDO")
			(pinfunction "JTAG_TDI")
			(pintype "bidirectional")
		)
		(pad "65" smd roundrect
			(at -2.275 -0.3 90)
			(size 0.3 0.45)
			(layers "F.Cu" "F.Mask" "F.Paste")
			(roundrect_rratio 0.18)
			(net 257 "WL_BT_TDO")
			(pinfunction "JTAG_TDO")
			(pintype "bidirectional")
		)
		(pad "66" smd roundrect
			(at -2.275 0.3 90)
			(size 0.3 0.45)
			(layers "F.Cu" "F.Mask" "F.Paste")
			(roundrect_rratio 0.18)
			(net 124 "JTAG_TCK")
			(pinfunction "JTAG_TCK/SWCLK")
			(pintype "bidirectional")
		)
		(pad "67" smd roundrect
			(at -2.275 0.9 90)
			(size 0.3 0.45)
			(layers "F.Cu" "F.Mask" "F.Paste")
			(roundrect_rratio 0.18)
			(net 123 "JTAG_TMS")
			(pinfunction "JTAG_TMS/SWDIO")
			(pintype "bidirectional")
		)
		(pad "68" smd roundrect
			(at -2.275 1.5 90)
			(size 0.3 0.45)
			(layers "F.Cu" "F.Mask" "F.Paste")
			(roundrect_rratio 0.18)
			(net 172 "BT_REG_ON")
			(pinfunction "BT_REG_EN")
			(pintype "input")
		)
		(pad "69" smd roundrect
			(at -1 1 180)
			(size 0.3 0.45)
			(layers "F.Cu" "F.Mask" "F.Paste")
			(roundrect_rratio 0.18)
			(net 417 "GND")
			(pinfunction "GND")
			(pintype "passive")
		)
		(pad "70" smd roundrect
			(at 0 1 180)
			(size 0.3 0.45)
			(layers "F.Cu" "F.Mask" "F.Paste")
			(roundrect_rratio 0.18)
			(net 417 "GND")
			(pinfunction "GND")
			(pintype "passive")
		)
		(pad "71" smd roundrect
			(at 1 1 180)
			(size 0.3 0.45)
			(layers "F.Cu" "F.Mask" "F.Paste")
			(roundrect_rratio 0.18)
			(net 417 "GND")
			(pinfunction "GND")
			(pintype "passive")
		)
		(pad "72" smd roundrect
			(at 1 0 180)
			(size 0.3 0.45)
			(layers "F.Cu" "F.Mask" "F.Paste")
			(roundrect_rratio 0.18)
			(net 417 "GND")
			(pinfunction "GND")
			(pintype "passive")
		)
		(pad "73" smd roundrect
			(at 1 -1 180)
			(size 0.3 0.45)
			(layers "F.Cu" "F.Mask" "F.Paste")
			(roundrect_rratio 0.18)
			(net 417 "GND")
			(pinfunction "GND")
			(pintype "passive")
		)
		(pad "74" smd roundrect
			(at 0 -1 180)
			(size 0.3 0.45)
			(layers "F.Cu" "F.Mask" "F.Paste")
			(roundrect_rratio 0.18)
			(net 417 "GND")
			(pinfunction "GND")
			(pintype "passive")
		)
		(pad "75" smd roundrect
			(at -1 -1 180)
			(size 0.3 0.45)
			(layers "F.Cu" "F.Mask" "F.Paste")
			(roundrect_rratio 0.18)
			(net 417 "GND")
			(pinfunction "GND")
			(pintype "passive")
		)
		(pad "76" smd roundrect
			(at -1 0 180)
			(size 0.3 0.45)
			(layers "F.Cu" "F.Mask" "F.Paste")
			(roundrect_rratio 0.18)
			(net 417 "GND")
			(pinfunction "GND")
			(pintype "passive")
		)
		(pad "77" smd roundrect
			(at 0 0 180)
			(size 0.3 0.45)
			(layers "F.Cu" "F.Mask" "F.Paste")
			(roundrect_rratio 0.18)
			(net 417 "GND")
			(pinfunction "GND")
			(pintype "passive")
		)
	)
)
